# T6G (Grand Teton) — schematic netlist excerpt (pin names and nets, part order shuffled) for the footprints in the layout excerpt that follows; sources: Cadence DE-HDL packaged netlist, KiCad conversion of 04192023_DAF0TMB3IC0_F0TG_MB_C_brd_V02_OCP.brd

R1106  Q_RES  200 1% CHIP  pkg 0201LF  page 309 : A = RT_CPU0_P3_SCAN_MODE ; B = GND
R8012  Q_RES  0 5% CHIP  pkg 0402LF  page 152 : A = HP_LVC3_SCM_HSC_PWRGD_R ; B = HP_LVC3_SCM_HSC_PWRGD
R6761  Q_RES  0 5% CHIP  pkg 0201LF  page 184 : A = SMB_RT_CPU0_P2_SCL ; B = SMB_RT_CPU0_P2_R_SCL

(kicad_pcb
	(version 20260206)
	(generator "pcbnew")
	(generator_version "10.0")
	(general
		(thickness 1.6)
		(legacy_teardrops no)
	)
	(paper "A4")
	(title_block
		(title "04192023_DAF0TMB3IC0_F0TG_MB_C_brd_V02_OCP.brd")
		(comment 1 "Grand Teton / footprints 6295-6297 of 8354")
	)
	(layers
		(0 "F.Cu" signal "TOP")
		(4 "In1.Cu" signal "GND")
		(6 "In2.Cu" signal "IN1")
		(8 "In3.Cu" signal "GND1")
		(10 "In4.Cu" signal "IN2")
		(12 "In5.Cu" signal "GND2")
		(14 "In6.Cu" signal "IN3")
		(16 "In7.Cu" signal "GND3")
		(18 "In8.Cu" signal "VCC")
		(20 "In9.Cu" signal "VCC1")
		(22 "In10.Cu" signal "GND4")
		(24 "In11.Cu" signal "IN4")
		(26 "In12.Cu" signal "GND5")
		(28 "In13.Cu" signal "IN5")
		(30 "In14.Cu" signal "GND6")
		(32 "In15.Cu" signal "IN6")
		(34 "In16.Cu" signal "GND7")
		(2 "B.Cu" signal "BOTTOM")
		(9 "F.Adhes" user "F.Adhesive")
		(11 "B.Adhes" user "B.Adhesive")
		(13 "F.Paste" user "Package Geometry/Pastemask Top")
		(15 "B.Paste" user "Package Geometry/Pastemask Bottom")
		(5 "F.SilkS" user "Ref Des/Silkscreen Top")
		(7 "B.SilkS" user "Ref Des/Silkscreen Bottom")
		(1 "F.Mask" user "Board Geometry/Soldermask Top")
		(3 "B.Mask" user "Board Geometry/Soldermask Bottom")
		(17 "Dwgs.User" user "User.Drawings")
		(19 "Cmts.User" user "User.Comments")
		(21 "Eco1.User" user "User.Eco1")
		(23 "Eco2.User" user "User.Eco2")
		(25 "Edge.Cuts" user "Board Geometry/Outline")
		(27 "Margin" user)
		(31 "F.CrtYd" user "Package Geometry/Place Bound Top")
		(29 "B.CrtYd" user "Package Geometry/Place Bound Bottom")
		(35 "F.Fab" user "Ref Des/Assembly Top")
		(33 "B.Fab" user "Ref Des/Assembly Bottom")
	)
	(footprint ""
		(layer "B.Cu")
		(at 173.101 -30.099 -90)
		(property "Reference" "R8012"
			(at 0 0 90)
			(layer "B.SilkS")
			(hide yes)
			(effects
				(font
					(size 1.27 1.27)
				)
				(justify mirror)
			)
		)
		(property "Value" ""
			(at 0 0 90)
			(layer "B.Fab")
			(effects
				(font
					(size 1.27 1.27)
				)
				(justify mirror)
			)
		)
		(duplicate_pad_numbers_are_jumpers no)
		(fp_line
			(start -0.7874 0.4064)
			(end 0.7874 0.4064)
			(stroke
				(width 0.1524)
				(type default)
			)
			(layer "B.SilkS")
		)
		(fp_line
			(start 0.7874 0.4064)
			(end 0.7874 -0.4064)
			(stroke
				(width 0.1524)
				(type default)
			)
			(layer "B.SilkS")
		)
		(fp_line
			(start -0.7874 -0.4064)
			(end -0.7874 0.4064)
			(stroke
				(width 0.1524)
				(type default)
			)
			(layer "B.SilkS")
		)
		(fp_line
			(start 0.7874 -0.4064)
			(end -0.7874 -0.4064)
			(stroke
				(width 0.1524)
				(type default)
			)
			(layer "B.SilkS")
		)
		(fp_line
			(start -0.67945 0.3048)
			(end -0.120396 0.3048)
			(stroke
				(width 0.1)
				(type default)
			)
			(layer "B.Fab")
		)
		(fp_line
			(start -0.120396 0.3048)
			(end -0.120396 0.2794)
			(stroke
				(width 0.1)
				(type default)
			)
			(layer "B.Fab")
		)
		(fp_line
			(start 0.12065 0.3048)
			(end 0.67945 0.3048)
			(stroke
				(width 0.1)
				(type default)
			)
			(layer "B.Fab")
		)
		(fp_line
			(start 0.67945 0.3048)
			(end 0.67945 -0.305054)
			(stroke
				(width 0.1)
				(type default)
			)
			(layer "B.Fab")
		)
		(fp_line
			(start -0.120396 0.2794)
			(end 0.12065 0.2794)
			(stroke
				(width 0.1)
				(type default)
			)
			(layer "B.Fab")
		)
		(fp_line
			(start 0.12065 0.2794)
			(end 0.12065 0.3048)
			(stroke
				(width 0.1)
				(type default)
			)
			(layer "B.Fab")
		)
		(fp_line
			(start -0.12065 -0.2794)
			(end -0.12065 -0.3048)
			(stroke
				(width 0.1)
				(type default)
			)
			(layer "B.Fab")
		)
		(fp_line
			(start 0.12065 -0.2794)
			(end -0.12065 -0.2794)
			(stroke
				(width 0.1)
				(type default)
			)
			(layer "B.Fab")
		)
		(fp_line
			(start -0.67945 -0.3048)
			(end -0.67945 0.3048)
			(stroke
				(width 0.1)
				(type default)
			)
			(layer "B.Fab")
		)
		(fp_line
			(start -0.12065 -0.3048)
			(end -0.67945 -0.3048)
			(stroke
				(width 0.1)
				(type default)
			)
			(layer "B.Fab")
		)
		(fp_line
			(start 0.12065 -0.305054)
			(end 0.12065 -0.2794)
			(stroke
				(width 0.1)
				(type default)
			)
			(layer "B.Fab")
		)
		(fp_line
			(start 0.67945 -0.305054)
			(end 0.12065 -0.305054)
			(stroke
				(width 0.1)
				(type default)
			)
			(layer "B.Fab")
		)
		(pad "1" smd circle
			(at 0.40005 0 90)
			(size 0 0)
			(layers "B.Cu" "B.Mask" "B.Paste")
			(net "HP_LVC3_SCM_HSC_PWRGD_R")
		)
		(pad "2" smd circle
			(at -0.40005 0 90)
			(size 0 0)
			(layers "B.Cu" "B.Mask" "B.Paste")
			(net "HP_LVC3_SCM_HSC_PWRGD")
		)
	)
	(footprint ""
		(layer "B.Cu")
		(at 366.36579 -392.1252 180)
		(property "Reference" "R1106"
			(at 0 0 0)
			(layer "B.SilkS")
			(hide yes)
			(effects
				(font
					(size 1.27 1.27)
				)
				(justify mirror)
			)
		)
		(property "Value" ""
			(at 0 0 0)
			(layer "B.Fab")
			(effects
				(font
					(size 1.27 1.27)
				)
				(justify mirror)
			)
		)
		(duplicate_pad_numbers_are_jumpers no)
		(fp_line
			(start 0.32512 0.175006)
			(end 0.32512 -0.175006)
			(stroke
				(width 0.1)
				(type default)
			)
			(layer "B.Fab")
		)
		(fp_line
			(start 0.32512 -0.175006)
			(end -0.32512 -0.175006)
			(stroke
				(width 0.1)
				(type default)
			)
			(layer "B.Fab")
		)
		(fp_line
			(start -0.32512 0.175006)
			(end 0.32512 0.175006)
			(stroke
				(width 0.1)
				(type default)
			)
			(layer "B.Fab")
		)
		(fp_line
			(start -0.32512 -0.175006)
			(end -0.32512 0.175006)
			(stroke
				(width 0.1)
				(type default)
			)
			(layer "B.Fab")
		)
		(pad "1" smd rect
			(at 0.2667 0)
			(size 0.3048 0.381)
			(layers "B.Cu" "B.Mask" "B.Paste")
			(net "RT_CPU0_P3_SCAN_MODE")
		)
		(pad "2" smd rect
			(at -0.2667 0 180)
			(size 0.3048 0.381)
			(layers "B.Cu" "B.Mask" "B.Paste")
			(net "GND")
		)
	)
	(footprint ""
		(layer "B.Cu")
		(at 230.6828 -334.01 180)
		(property "Reference" "R6761"
			(at 0 0 0)
			(layer "B.SilkS")
			(hide yes)
			(effects
				(font
					(size 1.27 1.27)
				)
				(justify mirror)
			)
		)
		(property "Value" ""
			(at 0 0 0)
			(layer "B.Fab")
			(effects
				(font
					(size 1.27 1.27)
				)
				(justify mirror)
			)
		)
		(duplicate_pad_numbers_are_jumpers no)
		(fp_line
			(start 0.32512 0.175006)
			(end 0.32512 -0.175006)
			(stroke
				(width 0.1)
				(type default)
			)
			(layer "B.Fab")
		)
		(fp_line
			(start 0.32512 -0.175006)
			(end -0.32512 -0.175006)
			(stroke
				(width 0.1)
				(type default)
			)
			(layer "B.Fab")
		)
		(fp_line
			(start -0.32512 0.175006)
			(end 0.32512 0.175006)
			(stroke
				(width 0.1)
				(type default)
			)
			(layer "B.Fab")
		)
		(fp_line
			(start -0.32512 -0.175006)
			(end -0.32512 0.175006)
			(stroke
				(width 0.1)
				(type default)
			)
			(layer "B.Fab")
		)
		(pad "1" smd rect
			(at 0.2667 0)
			(size 0.3048 0.381)
			(layers "B.Cu" "B.Mask" "B.Paste")
			(net "SMB_RT_CPU0_P2_SCL")
		)
		(pad "2" smd rect
			(at -0.2667 0 180)
			(size 0.3048 0.381)
			(layers "B.Cu" "B.Mask" "B.Paste")
			(net "SMB_RT_CPU0_P2_R_SCL")
		)
	)
)
